# T6G (Grand Teton) — schematic netlist excerpt (pin names and nets, part order shuffled) for the footprints in the layout excerpt that follows; sources: Cadence DE-HDL packaged netlist, KiCad conversion of 04192023_DAF0TMB3IC0_F0TG_MB_C_brd_V02_OCP.brd

C6598  Q_CAP_DIFFBUS  DIFF BUS_0.22UF 6.3V 20% X6S  pkg C0201  page 308 : \1\ = P5E_CPU0_P3_TX_BUF_C_DN<0> ; \2\ = P5E_CPU0_P3_TX_BUF_DN<0>
R3075  Q_RES  130 1% CHIP  pkg 0402LF  page 254 : A = LED_PWRGD_PS_PWROK_PLD ; B = P3V3_AUX
PC132_6  Q_CAP  22UF 16V 20% X6S  pkg C0805  page 213 : A = SW_P12V_AUX_PVDDCR_CPU0_P1_FLT ; B = GND

(kicad_pcb
	(version 20260206)
	(generator "pcbnew")
	(generator_version "10.0")
	(general
		(thickness 1.6)
		(legacy_teardrops no)
	)
	(paper "A4")
	(title_block
		(title "04192023_DAF0TMB3IC0_F0TG_MB_C_brd_V02_OCP.brd")
		(comment 1 "Grand Teton / footprints 5858-5860 of 8354")
	)
	(layers
		(0 "F.Cu" signal "TOP")
		(4 "In1.Cu" signal "GND")
		(6 "In2.Cu" signal "IN1")
		(8 "In3.Cu" signal "GND1")
		(10 "In4.Cu" signal "IN2")
		(12 "In5.Cu" signal "GND2")
		(14 "In6.Cu" signal "IN3")
		(16 "In7.Cu" signal "GND3")
		(18 "In8.Cu" signal "VCC")
		(20 "In9.Cu" signal "VCC1")
		(22 "In10.Cu" signal "GND4")
		(24 "In11.Cu" signal "IN4")
		(26 "In12.Cu" signal "GND5")
		(28 "In13.Cu" signal "IN5")
		(30 "In14.Cu" signal "GND6")
		(32 "In15.Cu" signal "IN6")
		(34 "In16.Cu" signal "GND7")
		(2 "B.Cu" signal "BOTTOM")
		(9 "F.Adhes" user "F.Adhesive")
		(11 "B.Adhes" user "B.Adhesive")
		(13 "F.Paste" user "Package Geometry/Pastemask Top")
		(15 "B.Paste" user "Package Geometry/Pastemask Bottom")
		(5 "F.SilkS" user "Ref Des/Silkscreen Top")
		(7 "B.SilkS" user "Ref Des/Silkscreen Bottom")
		(1 "F.Mask" user "Board Geometry/Soldermask Top")
		(3 "B.Mask" user "Board Geometry/Soldermask Bottom")
		(17 "Dwgs.User" user "User.Drawings")
		(19 "Cmts.User" user "User.Comments")
		(21 "Eco1.User" user "User.Eco1")
		(23 "Eco2.User" user "User.Eco2")
		(25 "Edge.Cuts" user "Board Geometry/Outline")
		(27 "Margin" user)
		(31 "F.CrtYd" user "Package Geometry/Place Bound Top")
		(29 "B.CrtYd" user "Package Geometry/Place Bound Bottom")
		(35 "F.Fab" user "Ref Des/Assembly Top")
		(33 "B.Fab" user "Ref Des/Assembly Bottom")
	)
	(footprint ""
		(layer "B.Cu")
		(at 320.571876 -66.708782 90)
		(property "Reference" "R3075"
			(at 0 0 90)
			(layer "B.SilkS")
			(hide yes)
			(effects
				(font
					(size 1.27 1.27)
				)
				(justify mirror)
			)
		)
		(property "Value" ""
			(at 0 0 90)
			(layer "B.Fab")
			(effects
				(font
					(size 1.27 1.27)
				)
				(justify mirror)
			)
		)
		(duplicate_pad_numbers_are_jumpers no)
		(fp_line
			(start 0.7874 -0.4064)
			(end -0.7874 -0.4064)
			(stroke
				(width 0.1524)
				(type default)
			)
			(layer "B.SilkS")
		)
		(fp_line
			(start -0.7874 -0.4064)
			(end -0.7874 0.4064)
			(stroke
				(width 0.1524)
				(type default)
			)
			(layer "B.SilkS")
		)
		(fp_line
			(start 0.7874 0.4064)
			(end 0.7874 -0.4064)
			(stroke
				(width 0.1524)
				(type default)
			)
			(layer "B.SilkS")
		)
		(fp_line
			(start -0.7874 0.4064)
			(end 0.7874 0.4064)
			(stroke
				(width 0.1524)
				(type default)
			)
			(layer "B.SilkS")
		)
		(fp_line
			(start 0.67945 -0.305054)
			(end 0.12065 -0.305054)
			(stroke
				(width 0.1)
				(type default)
			)
			(layer "B.Fab")
		)
		(fp_line
			(start 0.12065 -0.305054)
			(end 0.12065 -0.2794)
			(stroke
				(width 0.1)
				(type default)
			)
			(layer "B.Fab")
		)
		(fp_line
			(start -0.12065 -0.3048)
			(end -0.67945 -0.3048)
			(stroke
				(width 0.1)
				(type default)
			)
			(layer "B.Fab")
		)
		(fp_line
			(start -0.67945 -0.3048)
			(end -0.67945 0.3048)
			(stroke
				(width 0.1)
				(type default)
			)
			(layer "B.Fab")
		)
		(fp_line
			(start 0.12065 -0.2794)
			(end -0.12065 -0.2794)
			(stroke
				(width 0.1)
				(type default)
			)
			(layer "B.Fab")
		)
		(fp_line
			(start -0.12065 -0.2794)
			(end -0.12065 -0.3048)
			(stroke
				(width 0.1)
				(type default)
			)
			(layer "B.Fab")
		)
		(fp_line
			(start 0.12065 0.2794)
			(end 0.12065 0.3048)
			(stroke
				(width 0.1)
				(type default)
			)
			(layer "B.Fab")
		)
		(fp_line
			(start -0.120396 0.2794)
			(end 0.12065 0.2794)
			(stroke
				(width 0.1)
				(type default)
			)
			(layer "B.Fab")
		)
		(fp_line
			(start 0.67945 0.3048)
			(end 0.67945 -0.305054)
			(stroke
				(width 0.1)
				(type default)
			)
			(layer "B.Fab")
		)
		(fp_line
			(start 0.12065 0.3048)
			(end 0.67945 0.3048)
			(stroke
				(width 0.1)
				(type default)
			)
			(layer "B.Fab")
		)
		(fp_line
			(start -0.120396 0.3048)
			(end -0.120396 0.2794)
			(stroke
				(width 0.1)
				(type default)
			)
			(layer "B.Fab")
		)
		(fp_line
			(start -0.67945 0.3048)
			(end -0.120396 0.3048)
			(stroke
				(width 0.1)
				(type default)
			)
			(layer "B.Fab")
		)
		(pad "1" smd circle
			(at 0.40005 0 270)
			(size 0 0)
			(layers "B.Cu" "B.Mask" "B.Paste")
			(net "LED_PWRGD_PS_PWROK_PLD")
		)
		(pad "2" smd circle
			(at -0.40005 0 270)
			(size 0 0)
			(layers "B.Cu" "B.Mask" "B.Paste")
			(net "P3V3_AUX")
		)
	)
	(footprint ""
		(layer "B.Cu")
		(at 62.563248 -168.86682 -90)
		(property "Reference" "PC132_6"
			(at 0 0 90)
			(layer "B.SilkS")
			(hide yes)
			(effects
				(font
					(size 1.27 1.27)
				)
				(justify mirror)
			)
		)
		(property "Value" ""
			(at 0 0 90)
			(layer "B.Fab")
			(effects
				(font
					(size 1.27 1.27)
				)
				(justify mirror)
			)
		)
		(duplicate_pad_numbers_are_jumpers no)
		(fp_line
			(start -1.524 0.762)
			(end 1.524 0.762)
			(stroke
				(width 0.1524)
				(type default)
			)
			(layer "B.SilkS")
		)
		(fp_line
			(start 1.524 0.762)
			(end 1.524 -0.762)
			(stroke
				(width 0.1524)
				(type default)
			)
			(layer "B.SilkS")
		)
		(fp_line
			(start -1.524 -0.762)
			(end -1.524 0.762)
			(stroke
				(width 0.1524)
				(type default)
			)
			(layer "B.SilkS")
		)
		(fp_line
			(start 1.524 -0.762)
			(end -1.524 -0.762)
			(stroke
				(width 0.1524)
				(type default)
			)
			(layer "B.SilkS")
		)
		(fp_line
			(start -1.1049 0.724916)
			(end -1.1049 -0.724916)
			(stroke
				(width 0.1)
				(type default)
			)
			(layer "B.Fab")
		)
		(fp_line
			(start 1.1049 0.724916)
			(end -1.1049 0.724916)
			(stroke
				(width 0.1)
				(type default)
			)
			(layer "B.Fab")
		)
		(fp_line
			(start -1.1049 -0.724916)
			(end 1.1049 -0.724916)
			(stroke
				(width 0.1)
				(type default)
			)
			(layer "B.Fab")
		)
		(fp_line
			(start 1.1049 -0.724916)
			(end 1.1049 0.724916)
			(stroke
				(width 0.1)
				(type default)
			)
			(layer "B.Fab")
		)
		(pad "1" smd rect
			(at 0.889 0 270)
			(size 1.016 1.27)
			(layers "B.Cu" "B.Mask" "B.Paste")
			(net "SW_P12V_AUX_PVDDCR_CPU0_P1_FLT")
		)
		(pad "2" smd rect
			(at -0.889 0 270)
			(size 1.016 1.27)
			(layers "B.Cu" "B.Mask" "B.Paste")
			(net "GND")
		)
	)
	(footprint ""
		(layer "B.Cu")
		(at 372.400322 -416.899344 90)
		(property "Reference" "C6598"
			(at 0 0 90)
			(layer "B.SilkS")
			(hide yes)
			(effects
				(font
					(size 1.27 1.27)
				)
				(justify mirror)
			)
		)
		(property "Value" ""
			(at 0 0 90)
			(layer "B.Fab")
			(effects
				(font
					(size 1.27 1.27)
				)
				(justify mirror)
			)
		)
		(duplicate_pad_numbers_are_jumpers no)
		(fp_line
			(start 0.299974 -0.150114)
			(end -0.299974 -0.150114)
			(stroke
				(width 0.1)
				(type default)
			)
			(layer "B.Fab")
		)
		(fp_line
			(start -0.299974 -0.150114)
			(end -0.299974 0.150114)
			(stroke
				(width 0.1)
				(type default)
			)
			(layer "B.Fab")
		)
		(fp_line
			(start 0.299974 0.150114)
			(end 0.299974 -0.150114)
			(stroke
				(width 0.1)
				(type default)
			)
			(layer "B.Fab")
		)
		(fp_line
			(start -0.299974 0.150114)
			(end 0.299974 0.150114)
			(stroke
				(width 0.1)
				(type default)
			)
			(layer "B.Fab")
		)
		(pad "1" smd rect
			(at 0.2667 0 270)
			(size 0.3048 0.381)
			(layers "B.Cu" "B.Mask" "B.Paste")
			(net "P5E_CPU0_P3_TX_BUF_C_DN<0>")
		)
		(pad "2" smd rect
			(at -0.2667 0 270)
			(size 0.3048 0.381)
			(layers "B.Cu" "B.Mask" "B.Paste")
			(net "P5E_CPU0_P3_TX_BUF_DN<0>")
		)
	)
)
